(kicad_pcb
	(version 20241229)
	(generator "pcbnew")
	(generator_version "9.0")
	(general
		(thickness 1.711)
		(legacy_teardrops no)
	)
	(paper "A4")
	(title_block
		(title "Antmicro Baseboard for Jetson AGX Thor")
		(date "2026-02-18")
		(rev "1.1.0")
		(company "Antmicro Ltd")
		(comment 1 "www.antmicro.com")
		(comment 9 "footprints 786-787 of 1170")
	)
	(layers
		(0 "F.Cu" signal)
		(4 "In1.Cu" signal)
		(6 "In2.Cu" signal)
		(8 "In3.Cu" signal)
		(10 "In4.Cu" jumper)
		(12 "In5.Cu" signal)
		(14 "In6.Cu" signal)
		(16 "In7.Cu" signal)
		(18 "In8.Cu" signal)
		(2 "B.Cu" signal)
		(9 "F.Adhes" user "F.Adhesive")
		(11 "B.Adhes" user "B.Adhesive")
		(13 "F.Paste" user)
		(15 "B.Paste" user)
		(5 "F.SilkS" user "F.Silkscreen")
		(7 "B.SilkS" user "B.Silkscreen")
		(1 "F.Mask" user)
		(3 "B.Mask" user)
		(17 "Dwgs.User" user "User.Drawings")
		(19 "Cmts.User" user "User.Comments")
		(21 "Eco1.User" user "User.Eco1")
		(23 "Eco2.User" user "User.Eco2")
		(25 "Edge.Cuts" user)
		(27 "Margin" user)
		(31 "F.CrtYd" user "F.Courtyard")
		(29 "B.CrtYd" user "B.Courtyard")
		(35 "F.Fab" user)
		(33 "B.Fab" user)
	)
	(footprint "antmicro-footprints:QFN-32-1EP_5x5mm"
		(layer "B.Cu")
		(at 128.0345 146.571 -90)
		(property "Reference" "U14"
			(at -1.311 3.041 90)
			(layer "B.SilkS")
			(effects
				(font
					(size 0.7 0.7)
					(thickness 0.15)
				)
				(justify left bottom mirror)
			)
		)
		(property "Value" "SLB9673AU20FW2610XTMA1"
			(at -4.939 -3.91 90)
			(layer "B.Fab")
			(effects
				(font
					(size 0.7 0.7)
					(thickness 0.15)
				)
				(justify left bottom mirror)
			)
		)
		(property "Datasheet" "https://eu.mouser.com/datasheet/2/196/Infineon_OPTIGA_TPM_SLB_9673_FW26_DataSheet_v01_30-3363760.pdf"
			(at 0 0 90)
			(layer "B.Fab")
			(hide yes)
			(effects
				(font
					(size 1.27 1.27)
					(thickness 0.15)
				)
				(justify mirror)
			)
		)
		(property "Description" "Security ICs / Authentication ICs"
			(at 0 0 90)
			(layer "B.Fab")
			(hide yes)
			(effects
				(font
					(size 1.27 1.27)
					(thickness 0.15)
				)
				(justify mirror)
			)
		)
		(property "MPN" "SLB9673AU20FW2610XTMA1"
			(at 0 0 90)
			(unlocked yes)
			(layer "B.Fab")
			(hide yes)
			(effects
				(font
					(size 1 1)
					(thickness 0.15)
				)
				(justify mirror)
			)
		)
		(property "Manufacturer" "Infineon"
			(at 0 0 90)
			(unlocked yes)
			(layer "B.Fab")
			(hide yes)
			(effects
				(font
					(size 1 1)
					(thickness 0.15)
				)
				(justify mirror)
			)
		)
		(property "Author" "Antmicro"
			(at 0 0 90)
			(unlocked yes)
			(layer "B.Fab")
			(hide yes)
			(effects
				(font
					(size 1 1)
					(thickness 0.15)
				)
				(justify mirror)
			)
		)
		(property "License" "Apache-2.0"
			(at 0 0 90)
			(unlocked yes)
			(layer "B.Fab")
			(hide yes)
			(effects
				(font
					(size 1 1)
					(thickness 0.15)
				)
				(justify mirror)
			)
		)
		(sheetname "/Peripherals/")
		(sheetfile "peripherals.kicad_sch")
		(attr smd)
		(fp_line
			(start -2.221 2.551)
			(end -2.62 2.149)
			(stroke
				(width 0.15)
				(type solid)
			)
			(layer "B.SilkS")
		)
		(fp_line
			(start 2.581 2.551)
			(end 2.178 2.551)
			(stroke
				(width 0.15)
				(type solid)
			)
			(layer "B.SilkS")
		)
		(fp_line
			(start 2.581 2.551)
			(end 2.581 2.149)
			(stroke
				(width 0.15)
				(type solid)
			)
			(layer "B.SilkS")
		)
		(fp_line
			(start 2.581 -2.249)
			(end 2.581 -2.648)
			(stroke
				(width 0.15)
				(type solid)
			)
			(layer "B.SilkS")
		)
		(fp_line
			(start -2.62 -2.648)
			(end -2.62 -2.249)
			(stroke
				(width 0.15)
				(type solid)
			)
			(layer "B.SilkS")
		)
		(fp_line
			(start -2.221 -2.648)
			(end -2.62 -2.648)
			(stroke
				(width 0.15)
				(type solid)
			)
			(layer "B.SilkS")
		)
		(fp_line
			(start 2.581 -2.648)
			(end 2.178 -2.648)
			(stroke
				(width 0.15)
				(type solid)
			)
			(layer "B.SilkS")
		)
		(fp_circle
			(center -3.25 1.702)
			(end -3.2 1.702)
			(stroke
				(width 0.15)
				(type solid)
			)
			(fill yes)
			(layer "B.SilkS")
		)
		(fp_rect
			(start -1.446 0.175)
			(end -0.246 1.375)
			(stroke
				(width 0.2)
				(type solid)
			)
			(fill yes)
			(layer "B.Paste")
		)
		(fp_rect
			(start 0.203 0.175)
			(end 1.403 1.375)
			(stroke
				(width 0.2)
				(type solid)
			)
			(fill yes)
			(layer "B.Paste")
		)
		(fp_rect
			(start -1.446 -1.474)
			(end -0.246 -0.274)
			(stroke
				(width 0.2)
				(type solid)
			)
			(fill yes)
			(layer "B.Paste")
		)
		(fp_rect
			(start 0.203 -1.474)
			(end 1.403 -0.274)
			(stroke
				(width 0.2)
				(type solid)
			)
			(fill yes)
			(layer "B.Paste")
		)
		(fp_rect
			(start -2.74 2.75)
			(end 2.75 -2.74)
			(stroke
				(width 0.05)
				(type solid)
			)
			(fill no)
			(layer "B.CrtYd")
		)
		(fp_line
			(start -2.499 2.299)
			(end -2.298 2.5)
			(stroke
				(width 0.15)
				(type solid)
			)
			(layer "B.Fab")
		)
		(fp_rect
			(start -2.499 2.5)
			(end 2.5 -2.499)
			(stroke
				(width 0.15)
				(type solid)
			)
			(fill no)
			(layer "B.Fab")
		)
		(fp_text user "${REFERENCE}"
			(at -4.939 -7.11 90)
			(layer "B.Fab")
			(effects
				(font
					(size 0.7 0.7)
					(thickness 0.15)
				)
				(justify left bottom mirror)
			)
		)
		(fp_text user "License: Apache-2.0"
			(at -4.939 -5.91 90)
			(layer "B.Fab")
			(effects
				(font
					(size 0.7 0.7)
					(thickness 0.15)
				)
				(justify left bottom mirror)
			)
		)
		(fp_text user "Author: Antmicro"
			(at -4.939 -8.31 90)
			(layer "B.Fab")
			(effects
				(font
					(size 0.7 0.7)
					(thickness 0.15)
				)
				(justify left bottom mirror)
			)
		)
		(pad "1" smd rect
			(at -2.495 1.702)
			(size 0.28 0.85)
			(layers "B.Cu" "B.Mask" "B.Paste")
			(net 2 "+3V3")
			(pinfunction "VDD")
			(pintype "power_in")
			(solder_mask_margin 0.07)
		)
		(pad "2" smd rect
			(at -2.495 1.2)
			(size 0.28 0.85)
			(layers "B.Cu" "B.Mask" "B.Paste")
			(net 1 "GND")
			(pinfunction "GND")
			(pintype "power_in")
			(solder_mask_margin 0.07)
		)
		(pad "3" smd rect
			(at -2.495 0.701)
			(size 0.28 0.85)
			(layers "B.Cu" "B.Mask" "B.Paste")
			(net 1064 "unconnected-(U14-GPIO_00-Pad3)")
			(pinfunction "GPIO_00")
			(pintype "passive+no_connect")
			(solder_mask_margin 0.07)
		)
		(pad "4" smd rect
			(at -2.495 0.201)
			(size 0.28 0.85)
			(layers "B.Cu" "B.Mask" "B.Paste")
			(net 1068 "unconnected-(U14-GPIO_01-Pad4)")
			(pinfunction "GPIO_01")
			(pintype "passive+no_connect")
			(solder_mask_margin 0.07)
		)
		(pad "5" smd rect
			(at -2.495 -0.296)
			(size 0.28 0.85)
			(layers "B.Cu" "B.Mask" "B.Paste")
			(net 1072 "unconnected-(U14-NCI-Pad5)")
			(pinfunction "NCI")
			(pintype "no_connect")
			(solder_mask_margin 0.07)
		)
		(pad "6" smd rect
			(at -2.495 -0.8)
			(size 0.28 0.85)
			(layers "B.Cu" "B.Mask" "B.Paste")
			(net 1077 "unconnected-(U14-NC-Pad6)")
			(pinfunction "NC")
			(pintype "no_connect")
			(solder_mask_margin 0.07)
		)
		(pad "7" smd rect
			(at -2.495 -1.3)
			(size 0.28 0.85)
			(layers "B.Cu" "B.Mask" "B.Paste")
			(net 1069 "unconnected-(U14-GPIO_02-Pad7)")
			(pinfunction "GPIO_02")
			(pintype "passive+no_connect")
			(solder_mask_margin 0.07)
		)
		(pad "8" smd rect
			(at -2.495 -1.8)
			(size 0.28 0.85)
			(layers "B.Cu" "B.Mask" "B.Paste")
			(net 2 "+3V3")
			(pinfunction "NCI/VDD")
			(pintype "passive")
			(solder_mask_margin 0.07)
		)
		(pad "9" smd rect
			(at -1.768 -2.523)
			(size 0.85 0.28)
			(layers "B.Cu" "B.Mask" "B.Paste")
			(net 1 "GND")
			(pinfunction "GND")
			(pintype "passive")
			(solder_mask_margin 0.07)
		)
		(pad "10" smd rect
			(at -1.269 -2.523)
			(size 0.85 0.28)
			(layers "B.Cu" "B.Mask" "B.Paste")
			(net 1066 "unconnected-(U14-NCI-Pad10)")
			(pinfunction "NCI")
			(pintype "no_connect")
			(solder_mask_margin 0.07)
		)
		(pad "11" smd rect
			(at -0.772 -2.523)
			(size 0.85 0.28)
			(layers "B.Cu" "B.Mask" "B.Paste")
			(net 1061 "unconnected-(U14-NCI-Pad11)")
			(pinfunction "NCI")
			(pintype "no_connect")
			(solder_mask_margin 0.07)
		)
		(pad "12" smd rect
			(at -0.272 -2.523)
			(size 0.85 0.28)
			(layers "B.Cu" "B.Mask" "B.Paste")
			(net 1065 "unconnected-(U14-NCI-Pad12)")
			(pinfunction "NCI")
			(pintype "no_connect")
			(solder_mask_margin 0.07)
		)
		(pad "13" smd rect
			(at 0.229 -2.523)
			(size 0.85 0.28)
			(layers "B.Cu" "B.Mask" "B.Paste")
			(net 1074 "unconnected-(U14-NCI-Pad13)")
			(pinfunction "NCI")
			(pintype "no_connect")
			(solder_mask_margin 0.07)
		)
		(pad "14" smd rect
			(at 0.728 -2.523)
			(size 0.85 0.28)
			(layers "B.Cu" "B.Mask" "B.Paste")
			(net 2 "+3V3")
			(pinfunction "VDD")
			(pintype "passive")
			(solder_mask_margin 0.07)
		)
		(pad "15" smd rect
			(at 1.23 -2.523)
			(size 0.85 0.28)
			(layers "B.Cu" "B.Mask" "B.Paste")
			(net 1076 "unconnected-(U14-NCI-Pad15)")
			(pinfunction "NCI")
			(pintype "no_connect")
			(solder_mask_margin 0.07)
		)
		(pad "16" smd rect
			(at 1.73 -2.523)
			(size 0.85 0.28)
			(layers "B.Cu" "B.Mask" "B.Paste")
			(net 1 "GND")
			(pinfunction "NCI/GND")
			(pintype "passive")
			(solder_mask_margin 0.07)
		)
		(pad "17" smd rect
			(at 2.456 -1.8)
			(size 0.28 0.85)
			(layers "B.Cu" "B.Mask" "B.Paste")
			(net 1089 "Net-(Q1-D)")
			(pinfunction "RST#")
			(pintype "passive")
			(solder_mask_margin 0.07)
		)
		(pad "18" smd rect
			(at 2.456 -1.3)
			(size 0.28 0.85)
			(layers "B.Cu" "B.Mask" "B.Paste")
			(net 149 "/Peripherals/TPM_IRQ")
			(pinfunction "I2C_PIRQ#")
			(pintype "passive")
			(solder_mask_margin 0.07)
		)
		(pad "19" smd rect
			(at 2.456 -0.8)
			(size 0.28 0.85)
			(layers "B.Cu" "B.Mask" "B.Paste")
			(net 1067 "unconnected-(U14-NC-Pad19)")
			(pinfunction "NC")
			(pintype "no_connect")
			(solder_mask_margin 0.07)
		)
		(pad "20" smd rect
			(at 2.456 -0.296)
			(size 0.28 0.85)
			(layers "B.Cu" "B.Mask" "B.Paste")
			(net 2 "+3V3")
			(pinfunction "TEST#")
			(pintype "passive")
			(solder_mask_margin 0.07)
		)
		(pad "21" smd rect
			(at 2.456 0.201)
			(size 0.28 0.85)
			(layers "B.Cu" "B.Mask" "B.Paste")
			(net 1062 "unconnected-(U14-NC-Pad21)")
			(pinfunction "NC")
			(pintype "no_connect")
			(solder_mask_margin 0.07)
		)
		(pad "22" smd rect
			(at 2.456 0.701)
			(size 0.28 0.85)
			(layers "B.Cu" "B.Mask" "B.Paste")
			(net 2 "+3V3")
			(pinfunction "VDD")
			(pintype "passive")
			(solder_mask_margin 0.07)
		)
		(pad "23" smd rect
			(at 2.456 1.2)
			(size 0.28 0.85)
			(layers "B.Cu" "B.Mask" "B.Paste")
			(net 1 "GND")
			(pinfunction "GND")
			(pintype "passive")
			(solder_mask_margin 0.07)
		)
		(pad "24" smd rect
			(at 2.456 1.702)
			(size 0.28 0.85)
			(layers "B.Cu" "B.Mask" "B.Paste")
			(net 1063 "unconnected-(U14-NC-Pad24)")
			(pinfunction "NC")
			(pintype "no_connect")
			(solder_mask_margin 0.07)
		)
		(pad "25" smd rect
			(at 1.73 2.426)
			(size 0.85 0.28)
			(layers "B.Cu" "B.Mask" "B.Paste")
			(net 1073 "unconnected-(U14-NCI-Pad25)")
			(pinfunction "NCI")
			(pintype "no_connect")
			(solder_mask_margin 0.07)
		)
		(pad "26" smd rect
			(at 1.23 2.426)
			(size 0.85 0.28)
			(layers "B.Cu" "B.Mask" "B.Paste")
			(net 1071 "unconnected-(U14-NCI-Pad26)")
			(pinfunction "NCI")
			(pintype "no_connect")
			(solder_mask_margin 0.07)
		)
		(pad "27" smd rect
			(at 0.728 2.426)
			(size 0.85 0.28)
			(layers "B.Cu" "B.Mask" "B.Paste")
			(net 1075 "unconnected-(U14-NCI-Pad27)")
			(pinfunction "NCI")
			(pintype "no_connect")
			(solder_mask_margin 0.07)
		)
		(pad "28" smd rect
			(at 0.229 2.426)
			(size 0.85 0.28)
			(layers "B.Cu" "B.Mask" "B.Paste")
			(net 1060 "unconnected-(U14-NCI-Pad28)")
			(pinfunction "NCI")
			(pintype "no_connect")
			(solder_mask_margin 0.07)
		)
		(pad "29" smd rect
			(at -0.272 2.426)
			(size 0.85 0.28)
			(layers "B.Cu" "B.Mask" "B.Paste")
			(net 850 "/I2C_{SYS}.SDA")
			(pinfunction "SDA")
			(pintype "passive")
			(solder_mask_margin 0.07)
		)
		(pad "30" smd rect
			(at -0.772 2.426)
			(size 0.85 0.28)
			(layers "B.Cu" "B.Mask" "B.Paste")
			(net 853 "/I2C_{SYS}.SCL")
			(pinfunction "SCL")
			(pintype "passive")
			(solder_mask_margin 0.07)
		)
		(pad "31" smd rect
			(at -1.269 2.426)
			(size 0.85 0.28)
			(layers "B.Cu" "B.Mask" "B.Paste")
			(net 1070 "unconnected-(U14-NCI-Pad31)")
			(pinfunction "NCI")
			(pintype "no_connect")
			(solder_mask_margin 0.07)
		)
		(pad "32" smd rect
			(at -1.768 2.426)
			(size 0.85 0.28)
			(layers "B.Cu" "B.Mask" "B.Paste")
			(net 1 "GND")
			(pinfunction "GND")
			(pintype "passive")
			(solder_mask_margin 0.07)
		)
		(pad "33" smd rect
			(at -0.02 -0.048)
			(size 3.45 3.45)
			(layers "B.Cu" "B.Mask")
			(net 1 "GND")
			(pinfunction "EP")
			(pintype "passive")
		)
	)
	(footprint "antmicro-footprints:R_0402_1005Metric"
		(layer "B.Cu")
		(at 216.1 126.5)
		(descr "Resistor SMD 0402")
		(tags "resistor SMD 0402")
		(property "Reference" "R48"
			(at 1.029 -0.3 0)
			(layer "B.SilkS")
			(effects
				(font
					(size 0.7 0.7)
					(thickness 0.15)
				)
				(justify right top mirror)
			)
		)
		(property "Value" "R_0R_0402"
			(at -1.011843 -1.772046 0)
			(layer "B.Fab")
			(effects
				(font
					(size 0.7 0.7)
					(thickness 0.15)
				)
				(justify right top mirror)
			)
		)
		(property "Datasheet" "https://industrial.panasonic.com/cdbs/www-data/pdf/RDA0000/AOA0000C301.pdf"
			(at 0 0 0)
			(layer "B.Fab")
			(hide yes)
			(effects
				(font
					(size 1.27 1.27)
					(thickness 0.15)
				)
				(justify mirror)
			)
		)
		(property "Description" "SMD Chip Resistor, Jumper, 0 ohm, 100 mW, 0402 [1005 Metric], Thick Film, General Purpose"
			(at 0 0 0)
			(layer "B.Fab")
			(hide yes)
			(effects
				(font
					(size 1.27 1.27)
					(thickness 0.15)
				)
				(justify mirror)
			)
		)
		(property "Manufacturer" "Panasonic"
			(at 0 0 180)
			(unlocked yes)
			(layer "B.Fab")
			(hide yes)
			(effects
				(font
					(size 1 1)
					(thickness 0.15)
				)
				(justify mirror)
			)
		)
		(property "MPN" "ERJ2GE0R00X"
			(at 0 0 180)
			(unlocked yes)
			(layer "B.Fab")
			(hide yes)
			(effects
				(font
					(size 1 1)
					(thickness 0.15)
				)
				(justify mirror)
			)
		)
		(property "Val" "0R"
			(at 0 0 180)
			(unlocked yes)
			(layer "B.Fab")
			(hide yes)
			(effects
				(font
					(size 1 1)
					(thickness 0.15)
				)
				(justify mirror)
			)
		)
		(property "License" "Apache-2.0"
			(at 0 0 180)
			(unlocked yes)
			(layer "B.Fab")
			(hide yes)
			(effects
				(font
					(size 1 1)
					(thickness 0.15)
				)
				(justify mirror)
			)
		)
		(property "Author" "Antmicro"
			(at 0 0 180)
			(unlocked yes)
			(layer "B.Fab")
			(hide yes)
			(effects
				(font
					(size 1 1)
					(thickness 0.15)
				)
				(justify mirror)
			)
		)
		(property "Tolerance" "~"
			(at 0 0 180)
			(unlocked yes)
			(layer "B.Fab")
			(hide yes)
			(effects
				(font
					(size 1 1)
					(thickness 0.15)
				)
				(justify mirror)
			)
		)
		(property "Current" "1A"
			(at 0 0 180)
			(unlocked yes)
			(layer "B.Fab")
			(hide yes)
			(effects
				(font
					(size 1 1)
					(thickness 0.15)
				)
				(justify mirror)
			)
		)
		(sheetname "/USB Hub/")
		(sheetfile "usb_hub.kicad_sch")
		(attr smd)
		(fp_poly
			(pts
				(xy -0.925 0.47) (xy -0.925 -0.47) (xy 0.925 -0.47) (xy 0.925 0.47)
			)
			(stroke
				(width 0.05)
				(type default)
			)
			(fill no)
			(layer "B.CrtYd")
		)
		(fp_poly
			(pts
				(xy -0.5 0.25) (xy -0.5 -0.25) (xy 0.5 -0.25) (xy 0.5 0.25)
			)
			(stroke
				(width 0.15)
				(type solid)
			)
			(fill no)
			(layer "B.Fab")
		)
		(fp_text user "${REFERENCE}"
			(at -0.95 -3.168 0)
			(layer "B.Fab")
			(effects
				(font
					(size 0.7 0.7)
					(thickness 0.15)
				)
				(justify right top mirror)
			)
		)
		(fp_text user "Author: Antmicro"
			(at -0.95 -4.169 0)
			(layer "B.Fab")
			(effects
				(font
					(size 0.7 0.7)
					(thickness 0.15)
				)
				(justify right top mirror)
			)
		)
		(fp_text user "License: Apache-2.0"
			(at -0.949999 -5.169 0)
			(layer "B.Fab")
			(effects
				(font
					(size 0.7 0.7)
					(thickness 0.15)
				)
				(justify right top mirror)
			)
		)
		(pad "1" smd roundrect
			(at -0.48 0)
			(size 0.59 0.64)
			(layers "B.Cu" "B.Mask" "B.Paste")
			(roundrect_rratio 0.25)
			(net 1138 "Net-(U21-USB2DN_DP4)")
			(pintype "passive")
		)
		(pad "2" smd roundrect
			(at 0.48 0)
			(size 0.59 0.64)
			(layers "B.Cu" "B.Mask" "B.Paste")
			(roundrect_rratio 0.25)
			(net 2 "+3V3")
			(pintype "passive")
		)
	)
)
